(kicad_pcb
	(version 20221018)
	(generator pcbnew)
	(general
    (thickness 1.656)
  )
	(paper "A4")
	(title_block
    (title "SDI-MIPI Bridge")
    (date "2023-08-09")
    (rev "1.3.4")
    (company "Antmicro")
		(comment 9 "footprints 58-63 of 190")
	)
	(layers
    (0 "F.Cu" signal)
    (1 "In1.Cu" power)
    (2 "In2.Cu" power)
    (3 "In3.Cu" signal)
    (4 "In4.Cu" signal)
    (31 "B.Cu" signal)
    (32 "B.Adhes" user "B.Adhesive")
    (33 "F.Adhes" user "F.Adhesive")
    (34 "B.Paste" user)
    (35 "F.Paste" user)
    (36 "B.SilkS" user "B.Silkscreen")
    (37 "F.SilkS" user "F.Silkscreen")
    (38 "B.Mask" user)
    (39 "F.Mask" user)
    (40 "Dwgs.User" user "User.Drawings")
    (41 "Cmts.User" user "User.Comments")
    (42 "Eco1.User" user "User.Eco1")
    (43 "Eco2.User" user "User.Eco2")
    (44 "Edge.Cuts" user)
    (45 "Margin" user)
    (46 "B.CrtYd" user "B.Courtyard")
    (47 "F.CrtYd" user "F.Courtyard")
    (48 "B.Fab" user)
    (49 "F.Fab" user)
  )
	(footprint "sdi-mipi-bridge-footprints:R_0402_1005Metric" (layer "F.Cu")
    (at 143 131.75 90)
    (descr "Resistor SMD 0402")
    (tags "resistor SMD 0402")
    (property "Author" "Antmicro")
    (property "License" "Apache-2.0")
    (property "MPN" "CR0402-FX-1002GLF")
    (property "Manufacturer" "Bourns")
    (property "Sheetfile" "sdi-mipi-bridge.kicad_sch")
    (property "Sheetname" "")
    (property "Tolerance" "1%")
    (property "Val" "10k")
    (property "ki_description" "10k resistor in 0402 package with 1% tolerance")
    (attr smd)
    (fp_text reference "R81" (at -5.75 0.4 90) (layer "F.SilkS")
        (effects (font (size 0.65 0.65) (thickness 0.15)) (justify left bottom))
    )
    (fp_text value "R_10k_0402" (at 0 1.4 90) (layer "F.Fab") hide
        (effects (font (size 0.7 0.7) (thickness 0.15)) (justify left bottom))
    )
    (fp_text user "Author: Antmicro" (at -0.95 4.169 90) (layer "F.Fab") hide
        (effects (font (size 0.7 0.7) (thickness 0.15)) (justify left bottom))
    )
    (fp_text user "${REFERENCE}" (at -0.95 3.168 90) (layer "F.Fab") hide
        (effects (font (size 0.7 0.7) (thickness 0.15)) (justify left bottom))
    )
    (fp_text user "License: Apache-2.0" (at -0.95 5.169 90) (layer "F.Fab") hide
        (effects (font (size 0.7 0.7) (thickness 0.15)) (justify left bottom))
    )
    (fp_rect (start -0.93 -0.47) (end 0.93 0.47)
      (stroke (width 0.05) (type solid)) (fill none) (layer "F.CrtYd"))
    (fp_rect (start -0.5 -0.25) (end 0.5 0.25)
      (stroke (width 0.15) (type solid)) (fill none) (layer "F.Fab"))
    (pad "1" smd roundrect (at -0.485 0 90) (size 0.59 0.64) (layers "F.Cu" "F.Paste" "F.Mask") (roundrect_rratio 0.25)
      (net 3 "GNDA") (pintype "passive"))
    (pad "2" smd roundrect (at 0.485 0 90) (size 0.59 0.64) (layers "F.Cu" "F.Paste" "F.Mask") (roundrect_rratio 0.25)
      (net 16 "/20bit_~{10bit}") (pintype "passive"))
  )
	(footprint "sdi-mipi-bridge-footprints:R_0402_1005Metric" (layer "F.Cu")
    (at 144.25 129.75 90)
    (descr "Resistor SMD 0402")
    (tags "resistor SMD 0402")
    (property "Author" "Antmicro")
    (property "DNP" "")
    (property "License" "Apache-2.0")
    (property "MPN" "CR0402-FX-1002GLF")
    (property "Manufacturer" "Bourns")
    (property "Sheetfile" "sdi-mipi-bridge.kicad_sch")
    (property "Sheetname" "")
    (property "Tolerance" "1%")
    (property "Val" "10k")
    (property "ki_description" "10k resistor in 0402 package with 1% tolerance")
    (attr smd)
    (fp_text reference "R83" (at -5.75 0.4 90) (layer "F.SilkS")
        (effects (font (size 0.65 0.65) (thickness 0.15)) (justify left bottom))
    )
    (fp_text value "R_10k_0402" (at 0 1.4 90) (layer "F.Fab") hide
        (effects (font (size 0.7 0.7) (thickness 0.15)) (justify left bottom))
    )
    (fp_text user "Author: Antmicro" (at -0.95 4.169 90) (layer "F.Fab") hide
        (effects (font (size 0.7 0.7) (thickness 0.15)) (justify left bottom))
    )
    (fp_text user "License: Apache-2.0" (at -0.95 5.169 90) (layer "F.Fab") hide
        (effects (font (size 0.7 0.7) (thickness 0.15)) (justify left bottom))
    )
    (fp_text user "${REFERENCE}" (at -0.95 3.168 90) (layer "F.Fab") hide
        (effects (font (size 0.7 0.7) (thickness 0.15)) (justify left bottom))
    )
    (fp_rect (start -0.93 -0.47) (end 0.93 0.47)
      (stroke (width 0.05) (type solid)) (fill none) (layer "F.CrtYd"))
    (fp_rect (start -0.5 -0.25) (end 0.5 0.25)
      (stroke (width 0.15) (type solid)) (fill none) (layer "F.Fab"))
    (pad "1" smd roundrect (at -0.485 0 90) (size 0.59 0.64) (layers "F.Cu" "F.Paste" "F.Mask") (roundrect_rratio 0.25)
      (net 17 "/~{SMPTE_BYPASS}") (pintype "passive"))
    (pad "2" smd roundrect (at 0.485 0 90) (size 0.59 0.64) (layers "F.Cu" "F.Paste" "F.Mask") (roundrect_rratio 0.25)
      (net 76 "IO_VDD") (pintype "passive"))
  )
	(footprint "sdi-mipi-bridge-footprints:TSSOP-16_4.4x5mm_P0.65mm" (layer "F.Cu")
    (at 130.7 125.3)
    (property "Author" "Antmicro")
    (property "License" "Apache-2.0")
    (property "MPN" "SC18IS602BIPW")
    (property "Manufacturer" "NXP")
    (property "Sheetfile" "sdi-mipi-bridge.kicad_sch")
    (property "Sheetname" "")
    (attr smd)
    (fp_text reference "U5" (at -0.7 -3.1) (layer "F.SilkS")
        (effects (font (size 0.65 0.65) (thickness 0.15)) (justify left bottom))
    )
    (fp_text value "SC18IS602BIPW" (at 0 3.749) (layer "F.Fab") hide
        (effects (font (size 0.7 0.7) (thickness 0.15)) (justify left bottom))
    )
    (fp_text user "Author: Antmicro" (at -3.801 8.15) (layer "F.Fab") hide
        (effects (font (size 0.7 0.7) (thickness 0.15)) (justify left bottom))
    )
    (fp_text user "${REFERENCE}" (at -3.801 9.349) (layer "F.Fab") hide
        (effects (font (size 0.7 0.7) (thickness 0.15)) (justify left bottom))
    )
    (fp_text user "License: Apache-2.0" (at -3.801 5.749) (layer "F.Fab") hide
        (effects (font (size 0.7 0.7) (thickness 0.15)) (justify left bottom))
    )
    (fp_line (start -2.15 -2.735) (end 2.249 -2.735)
      (stroke (width 0.15) (type solid)) (layer "F.SilkS"))
    (fp_line (start 0.05 2.733) (end -2.15 2.733)
      (stroke (width 0.15) (type solid)) (layer "F.SilkS"))
    (fp_line (start 0.05 2.733) (end 2.249 2.733)
      (stroke (width 0.15) (type solid)) (layer "F.SilkS"))
    (fp_circle (center -2.45 -2.67071) (end -2.4 -2.62071)
      (stroke (width 0.15) (type solid)) (fill solid) (layer "F.SilkS"))
    (fp_line (start -3.81 -2.75) (end -3.81 2.74)
      (stroke (width 0.05) (type solid)) (layer "F.CrtYd"))
    (fp_line (start -3.81 2.74) (end 3.89 2.74)
      (stroke (width 0.05) (type solid)) (layer "F.CrtYd"))
    (fp_line (start 3.89 -2.75) (end -3.81 -2.75)
      (stroke (width 0.05) (type solid)) (layer "F.CrtYd"))
    (fp_line (start 3.89 2.74) (end 3.89 -2.75)
      (stroke (width 0.05) (type solid)) (layer "F.CrtYd"))
    (fp_line (start -2.15 -1.5) (end -1.151 -2.5)
      (stroke (width 0.15) (type solid)) (layer "F.Fab"))
    (fp_line (start -2.15 2.499) (end -2.15 -1.5)
      (stroke (width 0.15) (type solid)) (layer "F.Fab"))
    (fp_line (start -1.151 -2.5) (end 2.249 -2.5)
      (stroke (width 0.15) (type solid)) (layer "F.Fab"))
    (fp_line (start 2.249 -2.5) (end 2.249 2.499)
      (stroke (width 0.15) (type solid)) (layer "F.Fab"))
    (fp_line (start 2.249 2.499) (end -2.15 2.499)
      (stroke (width 0.15) (type solid)) (layer "F.Fab"))
    (pad "1" smd roundrect (at -2.814 -2.275) (size 1.475 0.4) (layers "F.Cu" "F.Paste" "F.Mask") (roundrect_rratio 0.25)
      (net 45 "/~{CS}_TMS") (pinfunction "GPIO0/~{SS0}") (pintype "bidirectional"))
    (pad "2" smd roundrect (at -2.814 -1.625) (size 1.475 0.4) (layers "F.Cu" "F.Paste" "F.Mask") (roundrect_rratio 0.25)
      (net 163 "unconnected-(U5-GPIO1{slash}~{SS1}-Pad2)") (pinfunction "GPIO1/~{SS1}") (pintype "bidirectional+no_connect"))
    (pad "3" smd roundrect (at -2.814 -0.975) (size 1.475 0.4) (layers "F.Cu" "F.Paste" "F.Mask") (roundrect_rratio 0.25)
      (net 72 "Net-(U5-~{RESET})") (pinfunction "~{RESET}") (pintype "input"))
    (pad "4" smd roundrect (at -2.814 -0.327) (size 1.475 0.4) (layers "F.Cu" "F.Paste" "F.Mask") (roundrect_rratio 0.25)
      (net 1 "GNDREF") (pinfunction "V_{SS}") (pintype "power_in"))
    (pad "5" smd roundrect (at -2.814 0.325) (size 1.475 0.4) (layers "F.Cu" "F.Paste" "F.Mask") (roundrect_rratio 0.25)
      (net 46 "/SDOUT_TDO") (pinfunction "MISO") (pintype "input"))
    (pad "6" smd roundrect (at -2.814 0.973) (size 1.475 0.4) (layers "F.Cu" "F.Paste" "F.Mask") (roundrect_rratio 0.25)
      (net 43 "/SDIN_TDI") (pinfunction "MOSI") (pintype "output"))
    (pad "7" smd roundrect (at -2.814 1.624) (size 1.475 0.4) (layers "F.Cu" "F.Paste" "F.Mask") (roundrect_rratio 0.25)
      (net 62 "/SDA_GS") (pinfunction "SDA") (pintype "bidirectional"))
    (pad "8" smd roundrect (at -2.814 2.273) (size 1.475 0.4) (layers "F.Cu" "F.Paste" "F.Mask") (roundrect_rratio 0.25)
      (net 61 "/SCL_GS") (pinfunction "SCL") (pintype "input"))
    (pad "9" smd roundrect (at 2.911 2.273) (size 1.475 0.4) (layers "F.Cu" "F.Paste" "F.Mask") (roundrect_rratio 0.25)
      (net 164 "unconnected-(U5-~{INT}-Pad9)") (pinfunction "~{INT}") (pintype "output+no_connect"))
    (pad "10" smd roundrect (at 2.911 1.624) (size 1.475 0.4) (layers "F.Cu" "F.Paste" "F.Mask") (roundrect_rratio 0.25)
      (net 100 "/CRESET_B") (pinfunction "GPIO2/~{SS2}") (pintype "bidirectional"))
    (pad "11" smd roundrect (at 2.911 0.973) (size 1.475 0.4) (layers "F.Cu" "F.Paste" "F.Mask") (roundrect_rratio 0.25)
      (net 42 "/SCLK_TCK") (pinfunction "SCLK") (pintype "output"))
    (pad "12" smd roundrect (at 2.911 0.325) (size 1.475 0.4) (layers "F.Cu" "F.Paste" "F.Mask") (roundrect_rratio 0.25)
      (net 6 "+3V3") (pinfunction "V_{DD}") (pintype "power_in"))
    (pad "13" smd roundrect (at 2.911 -0.327) (size 1.475 0.4) (layers "F.Cu" "F.Paste" "F.Mask") (roundrect_rratio 0.25)
      (net 165 "unconnected-(U5-GPIO3{slash}~{SS3}-Pad13)") (pinfunction "GPIO3/~{SS3}") (pintype "bidirectional+no_connect"))
    (pad "14" smd roundrect (at 2.911 -0.975) (size 1.475 0.4) (layers "F.Cu" "F.Paste" "F.Mask") (roundrect_rratio 0.25)
      (net 74 "Net-(U5-A0)") (pinfunction "A0") (pintype "input"))
    (pad "15" smd roundrect (at 2.911 -1.625) (size 1.475 0.4) (layers "F.Cu" "F.Paste" "F.Mask") (roundrect_rratio 0.25)
      (net 75 "Net-(U5-A1)") (pinfunction "A1") (pintype "input"))
    (pad "16" smd roundrect (at 2.911 -2.275) (size 1.475 0.4) (layers "F.Cu" "F.Paste" "F.Mask") (roundrect_rratio 0.25)
      (net 84 "Net-(U5-A2)") (pinfunction "A2") (pintype "input"))
  )
	(footprint "sdi-mipi-bridge-footprints:C_0402_1005Metric" (layer "F.Cu")
    (at 120.14 130.71 180)
    (descr "Capacitor SMD 0402")
    (tags "capacitor SMD 0402")
    (property "Author" "Antmicro")
    (property "Dielectric" "")
    (property "License" "Apache-2.0")
    (property "MPN" "0402N160J500CT")
    (property "Manufacturer" "Walsin")
    (property "Sheetfile" "sdi-mipi-bridge.kicad_sch")
    (property "Sheetname" "")
    (property "Val" "16p")
    (property "Voltage" "")
    (property "ki_description" " ")
    (attr smd)
    (fp_text reference "C59" (at 0.94 -0.39) (layer "F.SilkS")
        (effects (font (size 0.65 0.65) (thickness 0.15)) (justify right bottom))
    )
    (fp_text value "C_16p_0402" (at 0 1.4) (layer "F.Fab") hide
        (effects (font (size 0.7 0.7) (thickness 0.15)) (justify right bottom))
    )
    (fp_text user "${REFERENCE}" (at -0.932 3.168) (layer "F.Fab") hide
        (effects (font (size 0.7 0.7) (thickness 0.15)) (justify right bottom))
    )
    (fp_text user "Author: Antmicro" (at -0.932 4.17) (layer "F.Fab") hide
        (effects (font (size 0.7 0.7) (thickness 0.15)) (justify right bottom))
    )
    (fp_text user "License: Apache-2.0" (at -0.932 5.17) (layer "F.Fab") hide
        (effects (font (size 0.7 0.7) (thickness 0.15)) (justify right bottom))
    )
    (fp_rect (start -0.94 -0.47) (end 0.94 0.47)
      (stroke (width 0.05) (type solid)) (fill none) (layer "F.CrtYd"))
    (fp_rect (start -0.499 -0.249) (end 0.499 0.249)
      (stroke (width 0.15) (type solid)) (fill none) (layer "F.Fab"))
    (pad "1" smd roundrect (at -0.484 0 180) (size 0.59 0.64) (layers "F.Cu" "F.Paste" "F.Mask") (roundrect_rratio 0.25)
      (net 1 "GNDREF") (pintype "passive"))
    (pad "2" smd roundrect (at 0.484 0 180) (size 0.59 0.64) (layers "F.Cu" "F.Paste" "F.Mask") (roundrect_rratio 0.25)
      (net 7 "/XTAL2") (pintype "passive"))
  )
	(footprint "sdi-mipi-bridge-footprints:C_0402_1005Metric" (layer "F.Cu")
    (at 123.46 130.71)
    (descr "Capacitor SMD 0402")
    (tags "capacitor SMD 0402")
    (property "Author" "Antmicro")
    (property "Dielectric" "")
    (property "License" "Apache-2.0")
    (property "MPN" "0402N160J500CT")
    (property "Manufacturer" "Walsin")
    (property "Sheetfile" "sdi-mipi-bridge.kicad_sch")
    (property "Sheetname" "")
    (property "Val" "16p")
    (property "Voltage" "")
    (property "ki_description" " ")
    (attr smd)
    (fp_text reference "C60" (at -0.96 1.29) (layer "F.SilkS")
        (effects (font (size 0.65 0.65) (thickness 0.15)) (justify left bottom))
    )
    (fp_text value "C_16p_0402" (at 0 1.4) (layer "F.Fab") hide
        (effects (font (size 0.7 0.7) (thickness 0.15)) (justify left bottom))
    )
    (fp_text user "${REFERENCE}" (at -0.932 3.168) (layer "F.Fab") hide
        (effects (font (size 0.7 0.7) (thickness 0.15)) (justify left bottom))
    )
    (fp_text user "License: Apache-2.0" (at -0.932 5.17) (layer "F.Fab") hide
        (effects (font (size 0.7 0.7) (thickness 0.15)) (justify left bottom))
    )
    (fp_text user "Author: Antmicro" (at -0.932 4.17) (layer "F.Fab") hide
        (effects (font (size 0.7 0.7) (thickness 0.15)) (justify left bottom))
    )
    (fp_rect (start -0.94 -0.47) (end 0.94 0.47)
      (stroke (width 0.05) (type solid)) (fill none) (layer "F.CrtYd"))
    (fp_rect (start -0.499 -0.249) (end 0.499 0.249)
      (stroke (width 0.15) (type solid)) (fill none) (layer "F.Fab"))
    (pad "1" smd roundrect (at -0.484 0) (size 0.59 0.64) (layers "F.Cu" "F.Paste" "F.Mask") (roundrect_rratio 0.25)
      (net 1 "GNDREF") (pintype "passive"))
    (pad "2" smd roundrect (at 0.484 0) (size 0.59 0.64) (layers "F.Cu" "F.Paste" "F.Mask") (roundrect_rratio 0.25)
      (net 8 "/XTAL1") (pintype "passive"))
  )
	(footprint "sdi-mipi-bridge-footprints:Oscillator_SMD_Abracon_ABM7-2Pin_6x3.5mm" (layer "F.Cu")
    (at 121.8 128.15)
    (property "Author" "Antmicro")
    (property "License" "Apache-2.0")
    (property "MPN" "ABM7-27.000MHZ-D2Y-T")
    (property "Manufacturer" "Abracon")
    (property "Sheetfile" "sdi-mipi-bridge.kicad_sch")
    (property "Sheetname" "")
    (attr smd)
    (fp_text reference "Y1" (at -3.25 -2.25) (layer "F.SilkS")
        (effects (font (size 0.65 0.65) (thickness 0.15)) (justify left bottom))
    )
    (fp_text value "Oscillator_SMD_27MHz_ABM7" (at -3 3) (layer "F.Fab") hide
        (effects (font (size 0.7 0.7) (thickness 0.15)) (justify left bottom))
    )
    (fp_text user "License: Apache-2.0" (at -3 7) (layer "F.Fab") hide
        (effects (font (size 0.7 0.7) (thickness 0.15)) (justify left bottom))
    )
    (fp_text user "Author: Antmicro" (at -3.051 5.5) (layer "F.Fab") hide
        (effects (font (size 0.7 0.7) (thickness 0.15)) (justify left bottom))
    )
    (fp_text user "${REFERENCE}" (at -3.051 4.25) (layer "F.Fab") hide
        (effects (font (size 0.7 0.7) (thickness 0.15)) (justify left bottom))
    )
    (fp_line (start -3.102 -1.4745) (end -2.803 -1.7755)
      (stroke (width 0.15) (type solid)) (layer "F.SilkS"))
    (fp_line (start -3.102 1.499) (end -2.801 1.8)
      (stroke (width 0.15) (type solid)) (layer "F.SilkS"))
    (fp_line (start -2.803 -1.7755) (end 2.798 -1.7755)
      (stroke (width 0.15) (type solid)) (layer "F.SilkS"))
    (fp_line (start 2.8 1.8) (end -2.801 1.8)
      (stroke (width 0.15) (type solid)) (layer "F.SilkS"))
    (fp_line (start 3.099 -1.4745) (end 2.798 -1.7755)
      (stroke (width 0.15) (type solid)) (layer "F.SilkS"))
    (fp_line (start 3.099 1.499) (end 2.8 1.8)
      (stroke (width 0.15) (type solid)) (layer "F.SilkS"))
    (fp_rect (start -3.251 -1.95) (end 3.248 1.949)
      (stroke (width 0.05) (type solid)) (fill none) (layer "F.CrtYd"))
    (pad "1" smd rect (at -2.15 0) (size 1.9 2.6) (layers "F.Cu" "F.Paste" "F.Mask")
      (net 7 "/XTAL2") (pintype "passive"))
    (pad "2" smd rect (at 2.148 0) (size 1.9 2.6) (layers "F.Cu" "F.Paste" "F.Mask")
      (net 8 "/XTAL1") (pintype "passive"))
  )
)
